(kicad_pcb
	(version 20260206)
	(generator "pcbnew")
	(generator_version "10.0")
	(general
		(thickness 1.6)
		(legacy_teardrops no)
	)
	(paper "A4")
	(title_block
		(title "01162023_DA0F0TEBIF0_F0T_Expander_BD_F_brd_V02_OCP.brd")
		(comment 1 "Grand Teton / footprints 5465-5473 of 9728")
	)
	(layers
		(0 "F.Cu" signal "TOP")
		(4 "In1.Cu" signal "GND")
		(6 "In2.Cu" signal "VCC")
		(8 "In3.Cu" signal "VCC1")
		(10 "In4.Cu" signal "GND1")
		(12 "In5.Cu" signal "IN1")
		(14 "In6.Cu" signal "GND2")
		(16 "In7.Cu" signal "IN2")
		(18 "In8.Cu" signal "GND3")
		(20 "In9.Cu" signal "IN3")
		(22 "In10.Cu" signal "GND4")
		(24 "In11.Cu" signal "IN4")
		(26 "In12.Cu" signal "GND5")
		(28 "In13.Cu" signal "IN5")
		(30 "In14.Cu" signal "GND6")
		(32 "In15.Cu" signal "IN6")
		(34 "In16.Cu" signal "GND7")
		(2 "B.Cu" signal "BOTTOM")
		(9 "F.Adhes" user "F.Adhesive")
		(11 "B.Adhes" user "B.Adhesive")
		(13 "F.Paste" user "Package Geometry/Pastemask Top")
		(15 "B.Paste" user "Package Geometry/Pastemask Bottom")
		(5 "F.SilkS" user "Ref Des/Silkscreen Top")
		(7 "B.SilkS" user "Ref Des/Silkscreen Bottom")
		(1 "F.Mask" user "Board Geometry/Soldermask Top")
		(3 "B.Mask" user "Board Geometry/Soldermask Bottom")
		(17 "Dwgs.User" user "User.Drawings")
		(19 "Cmts.User" user "User.Comments")
		(21 "Eco1.User" user "User.Eco1")
		(23 "Eco2.User" user "User.Eco2")
		(25 "Edge.Cuts" user "Board Geometry/Outline")
		(27 "Margin" user)
		(31 "F.CrtYd" user "Package Geometry/Place Bound Top")
		(29 "B.CrtYd" user "Package Geometry/Place Bound Bottom")
		(35 "F.Fab" user "Ref Des/Assembly Top")
		(33 "B.Fab" user "Ref Des/Assembly Bottom")
	)
	(footprint ""
		(layer "F.Cu")
		(at 454.125838 -317.697358 180)
		(property "Reference" "PC1010"
			(at 0 0 180)
			(layer "F.SilkS")
			(hide yes)
			(effects
				(font
					(size 1.27 1.27)
				)
			)
		)
		(property "Value" ""
			(at 0 0 180)
			(layer "F.Fab")
			(effects
				(font
					(size 1.27 1.27)
				)
			)
		)
		(duplicate_pad_numbers_are_jumpers no)
		(fp_line
			(start 1.524 0.762)
			(end -1.524 0.762)
			(stroke
				(width 0.1524)
				(type default)
			)
			(layer "F.SilkS")
		)
		(fp_line
			(start 1.524 -0.762)
			(end 1.524 0.762)
			(stroke
				(width 0.1524)
				(type default)
			)
			(layer "F.SilkS")
		)
		(fp_line
			(start -1.524 0.762)
			(end -1.524 -0.762)
			(stroke
				(width 0.1524)
				(type default)
			)
			(layer "F.SilkS")
		)
		(fp_line
			(start -1.524 -0.762)
			(end 1.524 -0.762)
			(stroke
				(width 0.1524)
				(type default)
			)
			(layer "F.SilkS")
		)
		(fp_line
			(start 1.1049 0.724916)
			(end 1.1049 -0.724916)
			(stroke
				(width 0.1)
				(type default)
			)
			(layer "F.Fab")
		)
		(fp_line
			(start 1.1049 -0.724916)
			(end -1.1049 -0.724916)
			(stroke
				(width 0.1)
				(type default)
			)
			(layer "F.Fab")
		)
		(fp_line
			(start -1.1049 0.724916)
			(end 1.1049 0.724916)
			(stroke
				(width 0.1)
				(type default)
			)
			(layer "F.Fab")
		)
		(fp_line
			(start -1.1049 -0.724916)
			(end -1.1049 0.724916)
			(stroke
				(width 0.1)
				(type default)
			)
			(layer "F.Fab")
		)
		(pad "1" smd rect
			(at -0.889 0)
			(size 1.016 1.27)
			(layers "F.Cu" "F.Mask" "F.Paste")
			(net "SW_P12V_P1V25_PEX3_FLT")
		)
		(pad "2" smd rect
			(at 0.889 0)
			(size 1.016 1.27)
			(layers "F.Cu" "F.Mask" "F.Paste")
			(net "GND")
		)
	)
	(footprint ""
		(layer "F.Cu")
		(at 134.04723 -55.63489 90)
		(property "Reference" "PC359"
			(at 0 0 90)
			(layer "F.SilkS")
			(hide yes)
			(effects
				(font
					(size 1.27 1.27)
				)
			)
		)
		(property "Value" ""
			(at 0 0 90)
			(layer "F.Fab")
			(effects
				(font
					(size 1.27 1.27)
				)
			)
		)
		(duplicate_pad_numbers_are_jumpers no)
		(fp_line
			(start 1.524 -0.762)
			(end 1.524 0.762)
			(stroke
				(width 0.1524)
				(type default)
			)
			(layer "F.SilkS")
		)
		(fp_line
			(start -1.524 -0.762)
			(end 1.524 -0.762)
			(stroke
				(width 0.1524)
				(type default)
			)
			(layer "F.SilkS")
		)
		(fp_line
			(start 1.524 0.762)
			(end -1.524 0.762)
			(stroke
				(width 0.1524)
				(type default)
			)
			(layer "F.SilkS")
		)
		(fp_line
			(start -1.524 0.762)
			(end -1.524 -0.762)
			(stroke
				(width 0.1524)
				(type default)
			)
			(layer "F.SilkS")
		)
		(fp_line
			(start 1.1049 -0.724916)
			(end -1.1049 -0.724916)
			(stroke
				(width 0.1)
				(type default)
			)
			(layer "F.Fab")
		)
		(fp_line
			(start -1.1049 -0.724916)
			(end -1.1049 0.724916)
			(stroke
				(width 0.1)
				(type default)
			)
			(layer "F.Fab")
		)
		(fp_line
			(start 1.1049 0.724916)
			(end 1.1049 -0.724916)
			(stroke
				(width 0.1)
				(type default)
			)
			(layer "F.Fab")
		)
		(fp_line
			(start -1.1049 0.724916)
			(end 1.1049 0.724916)
			(stroke
				(width 0.1)
				(type default)
			)
			(layer "F.Fab")
		)
		(pad "1" smd rect
			(at -0.889 0 270)
			(size 1.016 1.27)
			(layers "F.Cu" "F.Mask" "F.Paste")
			(net "P12V_SSD4_R")
		)
		(pad "2" smd rect
			(at 0.889 0 270)
			(size 1.016 1.27)
			(layers "F.Cu" "F.Mask" "F.Paste")
			(net "GND")
		)
	)
	(footprint ""
		(layer "F.Cu")
		(at 337.349084 -350.098614 90)
		(property "Reference" "C525"
			(at 0 0 90)
			(layer "F.SilkS")
			(hide yes)
			(effects
				(font
					(size 1.27 1.27)
				)
			)
		)
		(property "Value" ""
			(at 0 0 90)
			(layer "F.Fab")
			(effects
				(font
					(size 1.27 1.27)
				)
			)
		)
		(duplicate_pad_numbers_are_jumpers no)
		(fp_line
			(start 0.299974 -0.150114)
			(end 0.299974 0.150114)
			(stroke
				(width 0.1)
				(type default)
			)
			(layer "F.Fab")
		)
		(fp_line
			(start -0.299974 -0.150114)
			(end 0.299974 -0.150114)
			(stroke
				(width 0.1)
				(type default)
			)
			(layer "F.Fab")
		)
		(fp_line
			(start 0.299974 0.150114)
			(end -0.299974 0.150114)
			(stroke
				(width 0.1)
				(type default)
			)
			(layer "F.Fab")
		)
		(fp_line
			(start -0.299974 0.150114)
			(end -0.299974 -0.150114)
			(stroke
				(width 0.1)
				(type default)
			)
			(layer "F.Fab")
		)
		(pad "1" smd rect
			(at -0.2667 0 90)
			(size 0.3048 0.381)
			(layers "F.Cu" "F.Mask" "F.Paste")
			(net "P5E_PEX2_STN5_TX_DP<92>")
		)
		(pad "2" smd rect
			(at 0.2667 0 90)
			(size 0.3048 0.381)
			(layers "F.Cu" "F.Mask" "F.Paste")
			(net "P5E_PEX2_STN5_TX_C_DP<92>")
		)
	)
	(footprint ""
		(layer "F.Cu")
		(at 343.567004 -350.098614 90)
		(property "Reference" "C519"
			(at 0 0 90)
			(layer "F.SilkS")
			(hide yes)
			(effects
				(font
					(size 1.27 1.27)
				)
			)
		)
		(property "Value" ""
			(at 0 0 90)
			(layer "F.Fab")
			(effects
				(font
					(size 1.27 1.27)
				)
			)
		)
		(duplicate_pad_numbers_are_jumpers no)
		(fp_line
			(start 0.299974 -0.150114)
			(end 0.299974 0.150114)
			(stroke
				(width 0.1)
				(type default)
			)
			(layer "F.Fab")
		)
		(fp_line
			(start -0.299974 -0.150114)
			(end 0.299974 -0.150114)
			(stroke
				(width 0.1)
				(type default)
			)
			(layer "F.Fab")
		)
		(fp_line
			(start 0.299974 0.150114)
			(end -0.299974 0.150114)
			(stroke
				(width 0.1)
				(type default)
			)
			(layer "F.Fab")
		)
		(fp_line
			(start -0.299974 0.150114)
			(end -0.299974 -0.150114)
			(stroke
				(width 0.1)
				(type default)
			)
			(layer "F.Fab")
		)
		(pad "1" smd rect
			(at -0.2667 0 90)
			(size 0.3048 0.381)
			(layers "F.Cu" "F.Mask" "F.Paste")
			(net "P5E_PEX2_STN5_TX_DP<95>")
		)
		(pad "2" smd rect
			(at 0.2667 0 90)
			(size 0.3048 0.381)
			(layers "F.Cu" "F.Mask" "F.Paste")
			(net "P5E_PEX2_STN5_TX_C_DP<95>")
		)
	)
	(footprint ""
		(layer "F.Cu")
		(at 198.76135 -124.991114 180)
		(property "Reference" "C236"
			(at 0 0 180)
			(layer "F.SilkS")
			(hide yes)
			(effects
				(font
					(size 1.27 1.27)
				)
			)
		)
		(property "Value" ""
			(at 0 0 180)
			(layer "F.Fab")
			(effects
				(font
					(size 1.27 1.27)
				)
			)
		)
		(duplicate_pad_numbers_are_jumpers no)
		(fp_line
			(start 0.299974 0.150114)
			(end -0.299974 0.150114)
			(stroke
				(width 0.1)
				(type default)
			)
			(layer "F.Fab")
		)
		(fp_line
			(start 0.299974 -0.150114)
			(end 0.299974 0.150114)
			(stroke
				(width 0.1)
				(type default)
			)
			(layer "F.Fab")
		)
		(fp_line
			(start -0.299974 0.150114)
			(end -0.299974 -0.150114)
			(stroke
				(width 0.1)
				(type default)
			)
			(layer "F.Fab")
		)
		(fp_line
			(start -0.299974 -0.150114)
			(end 0.299974 -0.150114)
			(stroke
				(width 0.1)
				(type default)
			)
			(layer "F.Fab")
		)
		(pad "1" smd rect
			(at -0.2667 0 180)
			(size 0.3048 0.381)
			(layers "F.Cu" "F.Mask" "F.Paste")
			(net "P5E_PEX1_STN0_TX_DP<3>")
		)
		(pad "2" smd rect
			(at 0.2667 0 180)
			(size 0.3048 0.381)
			(layers "F.Cu" "F.Mask" "F.Paste")
			(net "P5E_PEX1_STN0_TX_C_DP<3>")
		)
	)
	(footprint ""
		(layer "F.Cu")
		(at 195.226178 -37.929566 90)
		(property "Reference" "R5561"
			(at 0 0 90)
			(layer "F.SilkS")
			(hide yes)
			(effects
				(font
					(size 1.27 1.27)
				)
			)
		)
		(property "Value" ""
			(at 0 0 90)
			(layer "F.Fab")
			(effects
				(font
					(size 1.27 1.27)
				)
			)
		)
		(duplicate_pad_numbers_are_jumpers no)
		(fp_line
			(start 0.7874 -0.4064)
			(end 0.7874 0.4064)
			(stroke
				(width 0.1524)
				(type default)
			)
			(layer "F.SilkS")
		)
		(fp_line
			(start -0.7874 -0.4064)
			(end 0.7874 -0.4064)
			(stroke
				(width 0.1524)
				(type default)
			)
			(layer "F.SilkS")
		)
		(fp_line
			(start 0.7874 0.4064)
			(end -0.7874 0.4064)
			(stroke
				(width 0.1524)
				(type default)
			)
			(layer "F.SilkS")
		)
		(fp_line
			(start -0.7874 0.4064)
			(end -0.7874 -0.4064)
			(stroke
				(width 0.1524)
				(type default)
			)
			(layer "F.SilkS")
		)
		(fp_line
			(start -0.12065 -0.305054)
			(end -0.12065 -0.2794)
			(stroke
				(width 0.1)
				(type default)
			)
			(layer "F.Fab")
		)
		(fp_line
			(start -0.67945 -0.305054)
			(end -0.12065 -0.305054)
			(stroke
				(width 0.1)
				(type default)
			)
			(layer "F.Fab")
		)
		(fp_line
			(start 0.67945 -0.3048)
			(end 0.67945 0.3048)
			(stroke
				(width 0.1)
				(type default)
			)
			(layer "F.Fab")
		)
		(fp_line
			(start 0.12065 -0.3048)
			(end 0.67945 -0.3048)
			(stroke
				(width 0.1)
				(type default)
			)
			(layer "F.Fab")
		)
		(fp_line
			(start 0.12065 -0.2794)
			(end 0.12065 -0.3048)
			(stroke
				(width 0.1)
				(type default)
			)
			(layer "F.Fab")
		)
		(fp_line
			(start -0.12065 -0.2794)
			(end 0.12065 -0.2794)
			(stroke
				(width 0.1)
				(type default)
			)
			(layer "F.Fab")
		)
		(fp_line
			(start 0.120396 0.2794)
			(end -0.12065 0.2794)
			(stroke
				(width 0.1)
				(type default)
			)
			(layer "F.Fab")
		)
		(fp_line
			(start -0.12065 0.2794)
			(end -0.12065 0.3048)
			(stroke
				(width 0.1)
				(type default)
			)
			(layer "F.Fab")
		)
		(fp_line
			(start 0.67945 0.3048)
			(end 0.120396 0.3048)
			(stroke
				(width 0.1)
				(type default)
			)
			(layer "F.Fab")
		)
		(fp_line
			(start 0.120396 0.3048)
			(end 0.120396 0.2794)
			(stroke
				(width 0.1)
				(type default)
			)
			(layer "F.Fab")
		)
		(fp_line
			(start -0.12065 0.3048)
			(end -0.67945 0.3048)
			(stroke
				(width 0.1)
				(type default)
			)
			(layer "F.Fab")
		)
		(fp_line
			(start -0.67945 0.3048)
			(end -0.67945 -0.305054)
			(stroke
				(width 0.1)
				(type default)
			)
			(layer "F.Fab")
		)
		(pad "1" smd circle
			(at -0.40005 0 90)
			(size 0 0)
			(layers "F.Cu" "F.Mask" "F.Paste")
			(net "SSD7_AUX_P3V3_EN_R")
		)
		(pad "2" smd circle
			(at 0.40005 0 90)
			(size 0 0)
			(layers "F.Cu" "F.Mask" "F.Paste")
			(net "SSD7_AUX_P3V3_EN")
		)
	)
	(footprint ""
		(layer "F.Cu")
		(at 93.987874 -45.704252 90)
		(property "Reference" "R538"
			(at 0 0 90)
			(layer "F.SilkS")
			(hide yes)
			(effects
				(font
					(size 1.27 1.27)
				)
			)
		)
		(property "Value" ""
			(at 0 0 90)
			(layer "F.Fab")
			(effects
				(font
					(size 1.27 1.27)
				)
			)
		)
		(duplicate_pad_numbers_are_jumpers no)
		(fp_line
			(start 3.937508 -1.8796)
			(end -3.937508 -1.8796)
			(stroke
				(width 0.1524)
				(type default)
			)
			(layer "F.SilkS")
		)
		(fp_line
			(start -3.937508 -1.8796)
			(end -3.937508 1.8796)
			(stroke
				(width 0.1524)
				(type default)
			)
			(layer "F.SilkS")
		)
		(fp_line
			(start 3.937508 1.8796)
			(end 3.937508 -1.8796)
			(stroke
				(width 0.1524)
				(type default)
			)
			(layer "F.SilkS")
		)
		(fp_line
			(start -3.937508 1.8796)
			(end 3.937508 1.8796)
			(stroke
				(width 0.1524)
				(type default)
			)
			(layer "F.SilkS")
		)
		(fp_line
			(start 3.275076 -1.674876)
			(end -3.275076 -1.674876)
			(stroke
				(width 0.1)
				(type default)
			)
			(layer "F.Fab")
		)
		(fp_line
			(start -3.275076 -1.674876)
			(end -3.275076 1.674876)
			(stroke
				(width 0.1)
				(type default)
			)
			(layer "F.Fab")
		)
		(fp_line
			(start 3.275076 1.674876)
			(end 3.275076 -1.674876)
			(stroke
				(width 0.1)
				(type default)
			)
			(layer "F.Fab")
		)
		(fp_line
			(start -3.275076 1.674876)
			(end 3.275076 1.674876)
			(stroke
				(width 0.1)
				(type default)
			)
			(layer "F.Fab")
		)
		(pad "1" smd rect
			(at -2.350008 0 90)
			(size 2.921 3.5052)
			(layers "F.Cu" "F.Mask" "F.Paste")
			(net "P12V_SSD3")
		)
		(pad "2" smd rect
			(at 2.350008 0 90)
			(size 2.921 3.5052)
			(layers "F.Cu" "F.Mask" "F.Paste")
			(net "P12V_SSD3_R")
		)
	)
	(footprint ""
		(layer "F.Cu")
		(at 307.020468 -70.307454 90)
		(property "Reference" "PC868"
			(at 0 0 90)
			(layer "F.SilkS")
			(hide yes)
			(effects
				(font
					(size 1.27 1.27)
				)
			)
		)
		(property "Value" ""
			(at 0 0 90)
			(layer "F.Fab")
			(effects
				(font
					(size 1.27 1.27)
				)
			)
		)
		(duplicate_pad_numbers_are_jumpers no)
		(fp_line
			(start 0.7874 -0.4064)
			(end 0.7874 0.4064)
			(stroke
				(width 0.1524)
				(type default)
			)
			(layer "F.SilkS")
		)
		(fp_line
			(start -0.7874 -0.4064)
			(end 0.7874 -0.4064)
			(stroke
				(width 0.1524)
				(type default)
			)
			(layer "F.SilkS")
		)
		(fp_line
			(start 0.7874 0.4064)
			(end -0.7874 0.4064)
			(stroke
				(width 0.1524)
				(type default)
			)
			(layer "F.SilkS")
		)
		(fp_line
			(start -0.7874 0.4064)
			(end -0.7874 -0.4064)
			(stroke
				(width 0.1524)
				(type default)
			)
			(layer "F.SilkS")
		)
		(fp_line
			(start -0.12065 -0.305054)
			(end -0.12065 -0.2794)
			(stroke
				(width 0.1)
				(type default)
			)
			(layer "F.Fab")
		)
		(fp_line
			(start -0.67945 -0.305054)
			(end -0.12065 -0.305054)
			(stroke
				(width 0.1)
				(type default)
			)
			(layer "F.Fab")
		)
		(fp_line
			(start 0.67945 -0.3048)
			(end 0.67945 0.3048)
			(stroke
				(width 0.1)
				(type default)
			)
			(layer "F.Fab")
		)
		(fp_line
			(start 0.12065 -0.3048)
			(end 0.67945 -0.3048)
			(stroke
				(width 0.1)
				(type default)
			)
			(layer "F.Fab")
		)
		(fp_line
			(start 0.12065 -0.2794)
			(end 0.12065 -0.3048)
			(stroke
				(width 0.1)
				(type default)
			)
			(layer "F.Fab")
		)
		(fp_line
			(start -0.12065 -0.2794)
			(end 0.12065 -0.2794)
			(stroke
				(width 0.1)
				(type default)
			)
			(layer "F.Fab")
		)
		(fp_line
			(start 0.120396 0.2794)
			(end -0.12065 0.2794)
			(stroke
				(width 0.1)
				(type default)
			)
			(layer "F.Fab")
		)
		(fp_line
			(start -0.12065 0.2794)
			(end -0.12065 0.3048)
			(stroke
				(width 0.1)
				(type default)
			)
			(layer "F.Fab")
		)
		(fp_line
			(start 0.67945 0.3048)
			(end 0.120396 0.3048)
			(stroke
				(width 0.1)
				(type default)
			)
			(layer "F.Fab")
		)
		(fp_line
			(start 0.120396 0.3048)
			(end 0.120396 0.2794)
			(stroke
				(width 0.1)
				(type default)
			)
			(layer "F.Fab")
		)
		(fp_line
			(start -0.12065 0.3048)
			(end -0.67945 0.3048)
			(stroke
				(width 0.1)
				(type default)
			)
			(layer "F.Fab")
		)
		(fp_line
			(start -0.67945 0.3048)
			(end -0.67945 -0.305054)
			(stroke
				(width 0.1)
				(type default)
			)
			(layer "F.Fab")
		)
		(pad "1" smd circle
			(at -0.40005 0 90)
			(size 0 0)
			(layers "F.Cu" "F.Mask" "F.Paste")
			(net "P12V_AUX")
		)
		(pad "2" smd circle
			(at 0.40005 0 90)
			(size 0 0)
			(layers "F.Cu" "F.Mask" "F.Paste")
			(net "GND")
		)
	)
	(footprint ""
		(layer "F.Cu")
		(at 200.601834 -141.150848 -90)
		(property "Reference" "U24"
			(at 2.772918 -0.261366 0)
			(unlocked yes)
			(layer "F.SilkS")
			(effects
				(font
					(size 0.7874 0.5842)
					(thickness 0.1524)
				)
			)
		)
		(property "Value" ""
			(at 0 0 270)
			(layer "F.Fab")
			(effects
				(font
					(size 1.27 1.27)
				)
			)
		)
		(duplicate_pad_numbers_are_jumpers no)
		(fp_line
			(start -1.949958 1.610106)
			(end -1.949958 -1.610106)
			(stroke
				(width 0.1524)
				(type default)
			)
			(layer "F.SilkS")
		)
		(fp_line
			(start 1.949958 1.610106)
			(end -1.949958 1.610106)
			(stroke
				(width 0.1524)
				(type default)
			)
			(layer "F.SilkS")
		)
		(fp_line
			(start 1.949958 -1.560068)
			(end 1.949958 1.610106)
			(stroke
				(width 0.1524)
				(type default)
			)
			(layer "F.SilkS")
		)
		(fp_line
			(start -1.949958 -1.610106)
			(end 1.949958 -1.610106)
			(stroke
				(width 0.1524)
				(type default)
			)
			(layer "F.SilkS")
		)
		(fp_line
			(start -0.750062 1.560068)
			(end -0.750062 -1.560068)
			(stroke
				(width 0.1)
				(type default)
			)
			(layer "F.Fab")
		)
		(fp_line
			(start 0.750062 1.560068)
			(end -0.750062 1.560068)
			(stroke
				(width 0.1)
				(type default)
			)
			(layer "F.Fab")
		)
		(fp_line
			(start -0.750062 -1.560068)
			(end 0.750062 -1.560068)
			(stroke
				(width 0.1)
				(type default)
			)
			(layer "F.Fab")
		)
		(fp_line
			(start 0.750062 -1.560068)
			(end 0.750062 1.560068)
			(stroke
				(width 0.1)
				(type default)
			)
			(layer "F.Fab")
		)
		(pad "D" smd rect
			(at 1.100074 0 180)
			(size 1.016 1.4224)
			(layers "F.Cu" "F.Mask" "F.Paste")
			(net "HP_NIC3_EN")
		)
		(pad "G" smd rect
			(at -1.100074 -0.94996 180)
			(size 1.016 1.4224)
			(layers "F.Cu" "F.Mask" "F.Paste")
			(net "PRSNT_NIC3_R_N")
		)
		(pad "S" smd rect
			(at -1.100074 0.94996 180)
			(size 1.016 1.4224)
			(layers "F.Cu" "F.Mask" "F.Paste")
			(net "GND")
		)
	)
)
